FILE_TYPE = CONNECTIVITY;
{Allegro Design Entry HDL 16.6-p007 (v16-6-112F) 10/10/2012}
"PAGE_NUMBER" = 182;
0"NC";
1"P3E_CPU1_PE3_MP_RXP<15:8>";
2"P3E_CPU1_PE3_MP_RXN<15:8>";
3"P3E_CPU1_PE3_MP_TXN<15:8>";
4"P3E_CPU1_PE3_MP_TXP<15:8>";
5"GND\g";
6"GND\g";
7"P3E_CPU1_PE3_MP_TXP<8>";
8"P3E_CPU1_PE3_MP_TXP<13>";
9"P3E_CPU1_PE3_MP_TXN<13>";
10"P3E_CPU1_PE3_MP_TXP<12>";
11"P3E_CPU1_PE3_MP_TXN<10>";
12"P3E_CPU1_PE3_MP_TXP<10>";
13"P3E_CPU1_PE3_MP_TXP<9>";
14"P3E_CPU1_PE3_MP_TXN<9>";
15"P3E_CPU1_PE3_MP_TXN<8>";
16"P3E_CPU1_PE3_MP_TXN<12>";
17"P3E_CPU1_PE3_MP_TXN<15>";
18"P3E_CPU1_PE3_MP_TXP<14>";
19"P3E_CPU1_PE3_MP_TXN<14>";
20"P3E_CPU1_PE3_MP_TXP<15>";
21"P3E_CPU1_PE3_MP_TXN<11>";
22"P3E_CPU1_PE3_MP_TXP<11>";
23"P3E_CPU1_PE3_MP_C_TXN<15>";
24"P3E_CPU1_PE3_MP_C_TXP<15>";
25"P3E_CPU1_PE3_MP_C_TXN<11>";
26"P3E_CPU1_PE3_MP_C_TXP<11>";
27"P3E_CPU1_PE3_MP_C_TXN<12>";
28"P3E_CPU1_PE3_MP_C_TXP<12>";
29"P3E_CPU1_PE3_MP_C_TXN<13>";
30"P3E_CPU1_PE3_MP_C_TXP<13>";
31"TP_IOA5";
32"P3E_CPU1_PE3_MP_C_TXN<14>";
33"P3E_CPU1_PE3_MP_C_TXP<14>";
34"SMB_LAN_STBY_LVC3_SCL";
35"SMB_LAN_STBY_LVC3_SDA";
36"IRQ_BOARD_BMC_ALERT_N";
37"FM_XRC_PRESENT_N";
38"FM_XRC_READY_N";
39"SMB_PEHPCPU1_STBY_LVC3_SDA";
40"SMB_PEHPCPU1_STBY_LVC3_SCL";
41"P3E_CPU1_PE3_MP_C_TXP<8>";
42"P3E_CPU1_PE3_MP_C_TXN<9>";
43"P3E_CPU1_PE3_MP_C_TXP<9>";
44"P3E_CPU1_PE3_MP_C_TXP<10>";
45"P3E_CPU1_PE3_MP_C_TXN<8>";
46"P3E_CPU1_PE3_MP_C_TXN<10>";
47"P3E_CPU1_PE3_MP_RXN<13>";
48"P3E_CPU1_PE3_MP_RXP<13>";
49"P3E_CPU1_PE3_MP_RXP<12>";
50"P3E_CPU1_PE3_MP_RXN<12>";
51"P3E_CPU1_PE3_MP_RXN<11>";
52"P3E_CPU1_PE3_MP_RXP<11>";
53"P3E_CPU1_PE3_MP_RXP<9>";
54"P3E_CPU1_PE3_MP_RXN<9>";
55"P3E_CPU1_PE3_MP_RXP<8>";
56"P3E_CPU1_PE3_MP_RXN<8>";
57"P3E_CPU1_PE3_MP_RXN<14>";
58"P3E_CPU1_PE3_MP_RXP<10>";
59"P3E_CPU1_PE3_MP_RXN<10>";
60"P3E_CPU1_PE3_MP_RXP<14>";
61"P3E_CPU1_PE3_MP_RXN<15>";
62"P3E_CPU1_PE3_MP_RXP<15>";
63"TP_FM_WAKE_N";
64"TP_IOG3";
65"TP_IOH3";
66"TP_IOE4";
67"TP_IOF4";
68"TP_IOH4";
69"TP_IOI4";
70"FAN_TACH3_R";
71"FAN_TACH2_R";
72"FAN_PWM_OUT_SYS0_R1";
73"FAN_TACH0_R";
74"FM_BB_BMC_MP_GPIO";
75"FAN_TACH1_R";
76"SMB_LAN_STBY_LVC3_SDA";
77"IRQ_BOARD_BMC_ALERT_N";
78"FM_BMC_READY_N";
79"FM_XRC_READY_N";
80"SMB_LAN_STBY_LVC3_SCL";
%"RES"
"1","(-6550,750)","0","mstr_discrete","I101";
;
CDS_SEC"1"
ROOM"IO_SLOT"
SEC_TYPE"0402"
SEC"1"
NO_XNET_CONNECTION"1"
CDS_LIB"mstr_discrete"
CDS_LOCATION"R1C10"
PACK_TYPE"0402"
MATERIAL"EMPTY"
PART_NUMBER"G21497-005"
TOLERANCE"5%"
VALUE"0.0"
LOCATION"R1C10"
WATTAGE"1/16W";
"B"
$PN"2"70;
"A"
$PN"1"76;
%"RES"
"1","(-6550,625)","0","mstr_discrete","I104";
;
CDS_SEC"1"
NO_XNET_CONNECTION"1"
SEC"1"
SEC_TYPE"0402"
ROOM"IO_SLOT"
CDS_LIB"mstr_discrete"
CDS_LOCATION"R1C9"
PACK_TYPE"0402"
MATERIAL"EMPTY"
PART_NUMBER"G21497-005"
TOLERANCE"5%"
VALUE"0.0"
WATTAGE"1/16W"
LOCATION"R1C9";
"B"
$PN"2"71;
"A"
$PN"1"77;
%"RES"
"1","(-6550,500)","0","mstr_discrete","I107";
;
CDS_SEC"1"
ROOM"IO_SLOT"
NO_XNET_CONNECTION"1"
SEC"1"
SEC_TYPE"0402"
CDS_LIB"mstr_discrete"
CDS_LOCATION"R1F9"
PART_NUMBER"G21497-005"
PACK_TYPE"0402"
MATERIAL"EMPTY"
TOLERANCE"5%"
VALUE"0.0"
LOCATION"R1F9"
WATTAGE"1/16W";
"B"
$PN"2"72;
"A"
$PN"1"78;
%"RES"
"1","(-6550,350)","0","mstr_discrete","I110";
;
CDS_SEC"1"
NO_XNET_CONNECTION"1"
SEC"1"
SEC_TYPE"0402"
ROOM"IO_SLOT"
CDS_LIB"mstr_discrete"
CDS_LOCATION"R1C31"
PACK_TYPE"0402"
MATERIAL"EMPTY"
PART_NUMBER"G21497-005"
TOLERANCE"5%"
VALUE"0.0"
WATTAGE"1/16W"
LOCATION"R1C31";
"B"
$PN"2"73;
"A"
$PN"1"79;
%"CAP"
"2","(-2950,1950)","0","mstr_discrete","I12";
;
CDS_SEC"1"
ROOM"IO_SLOT"
SEC"1"
SEC_TYPE"0402"
BOM_COST"IO_SLOT"
CDS_LOCATION"C9N17"
CDS_LIB"mstr_discrete"
LOCATION"C9N17"
PART_NUMBER"A36096-155"
PACK_TYPE"0402"
TOLERANCE"10%"
MATERIAL"X7R"
VOLTAGE"16V"
VALUE"0.22UF";
"A"
$PN"1"41;
"B"
$PN"2"7;
%"CAP"
"2","(-2475,1850)","0","mstr_discrete","I13";
;
CDS_SEC"1"
SEC_TYPE"0402"
SEC"1"
ROOM"IO_SLOT"
BOM_COST"IO_SLOT"
CDS_LOCATION"C9N15"
CDS_LIB"mstr_discrete"
PACK_TYPE"0402"
PART_NUMBER"A36096-155"
TOLERANCE"10%"
MATERIAL"X7R"
VOLTAGE"16V"
LOCATION"C9N15"
VALUE"0.22UF";
"A"
$PN"1"42;
"B"
$PN"2"14;
%"CAP"
"2","(-2475,1700)","0","mstr_discrete","I14";
;
CDS_SEC"1"
SEC_TYPE"0402"
SEC"1"
ROOM"IO_SLOT"
BOM_COST"IO_SLOT"
CDS_LIB"mstr_discrete"
CDS_LOCATION"C9N1"
PACK_TYPE"0402"
PART_NUMBER"A36096-155"
TOLERANCE"10%"
MATERIAL"X7R"
VOLTAGE"16V"
LOCATION"C9N1"
VALUE"0.22UF";
"A"
$PN"1"44;
"B"
$PN"2"12;
%"CAP"
"2","(-2950,1650)","0","mstr_discrete","I15";
;
CDS_SEC"1"
SEC_TYPE"0402"
SEC"1"
BOM_COST"IO_SLOT"
ROOM"IO_SLOT"
CDS_LIB"mstr_discrete"
CDS_LOCATION"C9N2"
PACK_TYPE"0402"
TOLERANCE"10%"
MATERIAL"X7R"
PART_NUMBER"A36096-155"
VOLTAGE"16V"
LOCATION"C9N2"
VALUE"0.22UF";
"A"
$PN"1"46;
"B"
$PN"2"11;
%"CAP"
"2","(-2950,1800)","0","mstr_discrete","I16";
;
CDS_SEC"1"
SEC"1"
SEC_TYPE"0402"
BOM_COST"IO_SLOT"
ROOM"IO_SLOT"
CDS_LOCATION"C9N12"
CDS_LIB"mstr_discrete"
PACK_TYPE"0402"
TOLERANCE"10%"
MATERIAL"X7R"
PART_NUMBER"A36096-155"
VOLTAGE"16V"
LOCATION"C9N12"
VALUE"0.22UF";
"A"
$PN"1"43;
"B"
$PN"2"13;
%"GND"
"1","(-3750,1225)","0","mstr_symbols","I17";
;
VOLTAGE"0"
BOM_COST"NT_BASE_VRD"
CDS_LIB"mstr_symbols"
SIZE"1B"
BODY_TYPE"PLUMBING"
ROOM"P2V5_LAN_AUX_VR"
HDL_POWER"GND";
"A\NAC"5;
%"CONN76_H22707001"
"1","(-4425,2650)","0","mstr_conn","I18";
;
CDS_SEC"1"
BOM_COST"IO_SLOT"
PACK_TYPE"THMT1"
SEC_TYPE"THMT1"
SEC"1"
CDS_LOCATION"J1C1"
ROOM"IO_SLOT"
CDS_LIB"mstr_conn"
LOCATION"J1C1"
MATERIAL"CONN"
PART_NUMBER"H22707-001";
"GNDF5"
$PN"F5"5;
"IOG5"
$PN"G5"37;
"IOH5"
$PN"H5"38;
"GNDI5"
$PN"I5"5;
"GNDJ4"
$PN"J4"6;
"IOI4"
$PN"I4"69;
"IOH4"
$PN"H4"68;
"GNDG4"
$PN"G4"6;
"IOF4"
$PN"F4"67;
"IOE4"
$PN"E4"66;
"GNDD4"
$PN"D4"6;
"IOC4"
$PN"C4"74;
"GNDA4"
$PN"A4"6;
"GNDI3"
$PN"I3"6;
"IOH3"
$PN"H3"65;
"IOG3"
$PN"G3"64;
"GNDF3"
$PN"F3"6;
"IOE3"
$PN"E3"62;
"IOD3"
$PN"D3"61;
"GNDC3"
$PN"C3"6;
"IOA3"
$PN"A3"60;
"GNDJ2"
$PN"J2"6;
"IOF6"
$PN"F6"33;
"GNDG6"
$PN"G6"5;
"GNDJ8"
$PN"J8"5;
"IOI8"
$PN"I8"46;
"IOE6"
$PN"E6"32;
"GNDD6"
$PN"D6"5;
"IOC6"
$PN"C6"40;
"IOB6"
$PN"B6"39;
"GNDA6"
$PN"A6"5;
"IOB5"
$PN"B5"36;
"IOA5"
$PN"A5"31;
"GNDA2"
$PN"A2"6;
"GNDI1"
$PN"I1"6;
"IOH1"
$PN"H1"59;
"IOG1"
$PN"G1"58;
"IOB8"
$PN"B8"45;
"GNDA8"
$PN"A8"5;
"GNDI7"
$PN"I7"5;
"IOH8"
$PN"H8"44;
"IOF8"
$PN"F8"43;
"GNDG8"
$PN"G8"5;
"GNDD8"
$PN"D8"5;
"IOE8"
$PN"E8"42;
"IOC8"
$PN"C8"41;
"IOH7"
$PN"H7"30;
"IOG7"
$PN"G7"29;
"GNDF7"
$PN"F7"5;
"IOE7"
$PN"E7"28;
"IOD7"
$PN"D7"27;
"GNDC7"
$PN"C7"5;
"IOB7"
$PN"B7"26;
"IOA7"
$PN"A7"25;
"GNDJ6"
$PN"J6"5;
"IOI6"
$PN"I6"24;
"IOH6"
$PN"H6"23;
"IOE5"
$PN"E5"34;
"IOD5"
$PN"D5"35;
"GNDC5"
$PN"C5"5;
"IOB3"
$PN"B3"57;
"IOB4"
$PN"B4"63;
"IOA1"
$PN"A1"56;
"IOB1"
$PN"B1"55;
"GNDC1"
$PN"C1"6;
"IOD1"
$PN"D1"54;
"IOE1"
$PN"E1"53;
"GNDF1"
$PN"F1"6;
"IOC2"
$PN"C2"52;
"IOB2"
$PN"B2"51;
"IOE2"
$PN"E2"50;
"GNDD2"
$PN"D2"6;
"IOF2"
$PN"F2"49;
"GNDG2"
$PN"G2"6;
"IOH2"
$PN"H2"48;
"IOI2"
$PN"I2"47;
%"GND"
"1","(-5150,1275)","0","mstr_symbols","I19";
;
SIZE"1B"
CDS_LIB"mstr_symbols"
BODY_TYPE"PLUMBING"
ROOM"P2V5_LAN_AUX_VR"
HDL_POWER"GND"
BOM_COST"NT_BASE_VRD"
VOLTAGE"0";
"A\NAC"6;
%"TAP"
"6","(-1475,2000)","2","mstr_standard","I2";
;
CDS_LIB"mstr_standard"
BODY_TYPE"PLUMBING"
HDL_TAP"TRUE";
"B \NAC \NWC"3;
"S \NAC"
BN"8"15;
%"TAP"
"6","(-1725,1950)","2","mstr_standard","I4";
;
CDS_LIB"mstr_standard"
BODY_TYPE"PLUMBING"
HDL_TAP"TRUE";
"B \NAC \NWC"4;
"S \NAC"
BN"8"7;
%"TAP"
"6","(-1475,2900)","2","mstr_standard","I41";
;
CDS_LIB"mstr_standard"
BODY_TYPE"PLUMBING"
HDL_TAP"TRUE";
"B \NAC \NWC"3;
"S \NAC"
BN"14"19;
%"TAP"
"6","(-1475,2750)","2","mstr_standard","I42";
;
CDS_LIB"mstr_standard"
BODY_TYPE"PLUMBING"
HDL_TAP"TRUE";
"B \NAC \NWC"3;
"S \NAC"
BN"15"17;
%"TAP"
"6","(-1475,2550)","2","mstr_standard","I43";
;
CDS_LIB"mstr_standard"
BODY_TYPE"PLUMBING"
HDL_TAP"TRUE";
"B \NAC \NWC"3;
"S \NAC"
BN"11"21;
%"TAP"
"6","(-1725,2850)","2","mstr_standard","I44";
;
CDS_LIB"mstr_standard"
BODY_TYPE"PLUMBING"
HDL_TAP"TRUE";
"B \NAC \NWC"4;
"S \NAC"
BN"14"18;
%"TAP"
"6","(-1725,2700)","2","mstr_standard","I45";
;
CDS_LIB"mstr_standard"
BODY_TYPE"PLUMBING"
HDL_TAP"TRUE";
"B \NAC \NWC"4;
"S \NAC"
BN"15"20;
%"TAP"
"6","(-1725,2500)","2","mstr_standard","I46";
;
CDS_LIB"mstr_standard"
BODY_TYPE"PLUMBING"
HDL_TAP"TRUE";
"B \NAC \NWC"4;
"S \NAC"
BN"11"22;
%"TAP"
"6","(-1475,2400)","2","mstr_standard","I47";
;
CDS_LIB"mstr_standard"
BODY_TYPE"PLUMBING"
HDL_TAP"TRUE";
"B \NAC \NWC"3;
"S \NAC"
BN"12"16;
%"TAP"
"6","(-1725,2350)","2","mstr_standard","I48";
;
CDS_LIB"mstr_standard"
BODY_TYPE"PLUMBING"
HDL_TAP"TRUE";
"B \NAC \NWC"4;
"S \NAC"
BN"12"10;
%"CAP"
"2","(-2475,2750)","0","mstr_discrete","I49";
;
CDS_SEC"1"
ROOM"IO_SLOT"
CDS_LOCATION"C9N9"
SEC"1"
SEC_TYPE"0402"
BOM_COST"IO_SLOT"
CDS_LIB"mstr_discrete"
PACK_TYPE"0402"
TOLERANCE"10%"
MATERIAL"X7R"
PART_NUMBER"A36096-155"
VOLTAGE"16V"
LOCATION"C9N9"
VALUE"0.22UF";
"A"
$PN"1"23;
"B"
$PN"2"17;
%"TAP"
"6","(-1475,1850)","2","mstr_standard","I5";
;
CDS_LIB"mstr_standard"
BODY_TYPE"PLUMBING"
HDL_TAP"TRUE";
"B \NAC \NWC"3;
"S \NAC"
BN"9"14;
%"CAP"
"2","(-2475,2900)","0","mstr_discrete","I50";
;
CDS_SEC"1"
SEC_TYPE"0402"
SEC"1"
ROOM"IO_SLOT"
BOM_COST"IO_SLOT"
CDS_LOCATION"C9N8"
CDS_LIB"mstr_discrete"
PACK_TYPE"0402"
TOLERANCE"10%"
MATERIAL"X7R"
PART_NUMBER"A36096-155"
VOLTAGE"16V"
LOCATION"C9N8"
VALUE"0.22UF";
"A"
$PN"1"32;
"B"
$PN"2"19;
%"CAP"
"2","(-2475,2550)","0","mstr_discrete","I51";
;
CDS_SEC"1"
SEC_TYPE"0402"
SEC"1"
ROOM"IO_SLOT"
CDS_LOCATION"C9N3"
BOM_COST"IO_SLOT"
CDS_LIB"mstr_discrete"
PACK_TYPE"0402"
PART_NUMBER"A36096-155"
LOCATION"C9N3"
TOLERANCE"10%"
MATERIAL"X7R"
VOLTAGE"16V"
VALUE"0.22UF";
"A"
$PN"1"25;
"B"
$PN"2"21;
%"CAP"
"2","(-2475,2400)","0","mstr_discrete","I52";
;
CDS_SEC"1"
ROOM"IO_SLOT"
SEC"1"
SEC_TYPE"0402"
BOM_COST"IO_SLOT"
CDS_LOCATION"C9N16"
CDS_LIB"mstr_discrete"
PACK_TYPE"0402"
TOLERANCE"10%"
MATERIAL"X7R"
PART_NUMBER"A36096-155"
VOLTAGE"16V"
LOCATION"C9N16"
VALUE"0.22UF";
"A"
$PN"1"27;
"B"
$PN"2"16;
%"CAP"
"2","(-2950,2850)","0","mstr_discrete","I53";
;
CDS_SEC"1"
SEC_TYPE"0402"
SEC"1"
ROOM"IO_SLOT"
BOM_COST"IO_SLOT"
CDS_LIB"mstr_discrete"
CDS_LOCATION"C9N10"
PACK_TYPE"0402"
TOLERANCE"10%"
MATERIAL"X7R"
VOLTAGE"16V"
LOCATION"C9N10"
VALUE"0.22UF"
PART_NUMBER"A36096-155";
"A"
$PN"1"33;
"B"
$PN"2"18;
%"CAP"
"2","(-2950,2700)","0","mstr_discrete","I54";
;
CDS_SEC"1"
ROOM"IO_SLOT"
SEC"1"
BOM_COST"IO_SLOT"
SEC_TYPE"0402"
CDS_LIB"mstr_discrete"
CDS_LOCATION"C9N7"
PACK_TYPE"0402"
TOLERANCE"10%"
MATERIAL"X7R"
PART_NUMBER"A36096-155"
VOLTAGE"16V"
LOCATION"C9N7"
VALUE"0.22UF";
"A"
$PN"1"24;
"B"
$PN"2"20;
%"CAP"
"2","(-2950,2500)","0","mstr_discrete","I55";
;
CDS_SEC"1"
ROOM"IO_SLOT"
CDS_LOCATION"C9N4"
SEC"1"
SEC_TYPE"0402"
BOM_COST"IO_SLOT"
CDS_LIB"mstr_discrete"
PACK_TYPE"0402"
TOLERANCE"10%"
PART_NUMBER"A36096-155"
LOCATION"C9N4"
MATERIAL"X7R"
VOLTAGE"16V"
VALUE"0.22UF";
"A"
$PN"1"26;
"B"
$PN"2"22;
%"CAP"
"2","(-2950,2350)","0","mstr_discrete","I56";
;
CDS_SEC"1"
SEC"1"
SEC_TYPE"0402"
ROOM"IO_SLOT"
BOM_COST"IO_SLOT"
CDS_LOCATION"C9N14"
CDS_LIB"mstr_discrete"
PACK_TYPE"0402"
PART_NUMBER"A36096-155"
TOLERANCE"10%"
MATERIAL"X7R"
VOLTAGE"16V"
LOCATION"C9N14"
VALUE"0.22UF";
"A"
$PN"1"28;
"B"
$PN"2"10;
%"TAP"
"1","(-5400,3550)","2","mstr_standard","I57";
;
BODY_TYPE"PLUMBING"
CDS_LIB"mstr_standard"
HDL_TAP"TRUE";
"B \NAC \NWC"1;
"S \NAC"
BN"8"55;
%"TAP"
"1","(-5650,3600)","2","mstr_standard","I58";
;
CDS_LIB"mstr_standard"
BODY_TYPE"PLUMBING"
HDL_TAP"TRUE";
"B \NAC \NWC"2;
"S \NAC"
BN"8"56;
%"TAP"
"1","(-5400,3400)","2","mstr_standard","I59";
;
BODY_TYPE"PLUMBING"
CDS_LIB"mstr_standard"
HDL_TAP"TRUE";
"B \NAC \NWC"1;
"S \NAC"
BN"9"53;
%"TAP"
"6","(-1475,1650)","2","mstr_standard","I6";
;
CDS_LIB"mstr_standard"
BODY_TYPE"PLUMBING"
HDL_TAP"TRUE";
"B \NAC \NWC"3;
"S \NAC"
BN"10"11;
%"TAP"
"1","(-5400,3300)","2","mstr_standard","I60";
;
BODY_TYPE"PLUMBING"
CDS_LIB"mstr_standard"
HDL_TAP"TRUE";
"B \NAC \NWC"1;
"S \NAC"
BN"10"58;
%"TAP"
"1","(-5400,3000)","2","mstr_standard","I61";
;
BODY_TYPE"PLUMBING"
CDS_LIB"mstr_standard"
HDL_TAP"TRUE";
"B \NAC \NWC"1;
"S \NAC"
BN"11"52;
%"TAP"
"1","(-5650,3450)","2","mstr_standard","I62";
;
CDS_LIB"mstr_standard"
BODY_TYPE"PLUMBING"
HDL_TAP"TRUE";
"B \NAC \NWC"2;
"S \NAC"
BN"9"54;
%"TAP"
"1","(-5650,3250)","2","mstr_standard","I63";
;
BODY_TYPE"PLUMBING"
CDS_LIB"mstr_standard"
HDL_TAP"TRUE";
"B \NAC \NWC"2;
"S \NAC"
BN"10"59;
%"TAP"
"1","(-5650,3050)","2","mstr_standard","I64";
;
BODY_TYPE"PLUMBING"
CDS_LIB"mstr_standard"
HDL_TAP"TRUE";
"B \NAC \NWC"2;
"S \NAC"
BN"11"51;
%"TAP"
"1","(-5400,2850)","2","mstr_standard","I67";
;
BODY_TYPE"PLUMBING"
CDS_LIB"mstr_standard"
HDL_TAP"TRUE";
"B \NAC \NWC"1;
"S \NAC"
BN"12"49;
%"TAP"
"1","(-5400,2750)","2","mstr_standard","I68";
;
BODY_TYPE"PLUMBING"
CDS_LIB"mstr_standard"
HDL_TAP"TRUE";
"B \NAC \NWC"1;
"S \NAC"
BN"13"48;
%"TAP"
"1","(-5400,2550)","2","mstr_standard","I69";
;
BODY_TYPE"PLUMBING"
CDS_LIB"mstr_standard"
HDL_TAP"TRUE";
"B \NAC \NWC"1;
"S \NAC"
BN"14"60;
%"TAP"
"6","(-1725,1800)","2","mstr_standard","I7";
;
CDS_LIB"mstr_standard"
BODY_TYPE"PLUMBING"
HDL_TAP"TRUE";
"B \NAC \NWC"4;
"S \NAC"
BN"9"13;
%"TAP"
"1","(-5650,2900)","2","mstr_standard","I70";
;
CDS_LIB"mstr_standard"
BODY_TYPE"PLUMBING"
HDL_TAP"TRUE";
"B \NAC \NWC"2;
"S \NAC"
BN"12"50;
%"TAP"
"1","(-5650,2700)","2","mstr_standard","I71";
;
CDS_LIB"mstr_standard"
BODY_TYPE"PLUMBING"
HDL_TAP"TRUE";
"B \NAC \NWC"2;
"S \NAC"
BN"13"47;
%"TAP"
"1","(-5650,2500)","2","mstr_standard","I72";
;
BODY_TYPE"PLUMBING"
CDS_LIB"mstr_standard"
HDL_TAP"TRUE";
"B \NAC \NWC"2;
"S \NAC"
BN"14"57;
%"TAP"
"1","(-5400,2350)","2","mstr_standard","I73";
;
BODY_TYPE"PLUMBING"
CDS_LIB"mstr_standard"
HDL_TAP"TRUE";
"B \NAC \NWC"1;
"S \NAC"
BN"15"62;
%"TAP"
"1","(-5650,2400)","2","mstr_standard","I74";
;
CDS_LIB"mstr_standard"
BODY_TYPE"PLUMBING"
HDL_TAP"TRUE";
"B \NAC \NWC"2;
"S \NAC"
BN"15"61;
%"TAP"
"6","(-1725,1700)","2","mstr_standard","I8";
;
CDS_LIB"mstr_standard"
BODY_TYPE"PLUMBING"
HDL_TAP"TRUE";
"B \NAC \NWC"4;
"S \NAC"
BN"10"12;
%"CAP"
"2","(-2950,2250)","0","mstr_discrete","I81";
;
CDS_SEC"1"
SEC"1"
ROOM"IO_SLOT"
SEC_TYPE"0402"
BOM_COST"IO_SLOT"
CDS_LOCATION"C9N6"
CDS_LIB"mstr_discrete"
PACK_TYPE"0402"
PART_NUMBER"A36096-155"
TOLERANCE"10%"
MATERIAL"X7R"
VOLTAGE"16V"
LOCATION"C9N6"
VALUE"0.22UF";
"A"
$PN"1"29;
"B"
$PN"2"9;
%"TAP"
"6","(-1475,2250)","2","mstr_standard","I82";
;
CDS_LIB"mstr_standard"
BODY_TYPE"PLUMBING"
HDL_TAP"TRUE";
"B \NAC \NWC"3;
"S \NAC"
BN"13"9;
%"CAP"
"2","(-2475,2200)","0","mstr_discrete","I83";
;
CDS_SEC"1"
ROOM"IO_SLOT"
SEC"1"
BOM_COST"IO_SLOT"
SEC_TYPE"0402"
CDS_LOCATION"C9N5"
CDS_LIB"mstr_discrete"
PACK_TYPE"0402"
TOLERANCE"10%"
MATERIAL"X7R"
PART_NUMBER"A36096-155"
VOLTAGE"16V"
LOCATION"C9N5"
VALUE"0.22UF";
"A"
$PN"1"30;
"B"
$PN"2"8;
%"TAP"
"6","(-1725,2200)","2","mstr_standard","I84";
;
CDS_LIB"mstr_standard"
BODY_TYPE"PLUMBING"
HDL_TAP"TRUE";
"B \NAC \NWC"4;
"S \NAC"
BN"13"8;
%"CAP"
"2","(-2475,2000)","0","mstr_discrete","I9";
;
CDS_SEC"1"
ROOM"IO_SLOT"
CDS_LOCATION"C9N18"
SEC"1"
BOM_COST"IO_SLOT"
SEC_TYPE"0402"
CDS_LIB"mstr_discrete"
PACK_TYPE"0402"
PART_NUMBER"A36096-155"
LOCATION"C9N18"
TOLERANCE"10%"
MATERIAL"X7R"
VOLTAGE"16V"
VALUE"0.22UF";
"A"
$PN"1"45;
"B"
$PN"2"15;
%"RES"
"1","(-6550,875)","0","mstr_discrete","I97";
;
CDS_SEC"1"
SEC_TYPE"0402"
SEC"1"
NO_XNET_CONNECTION"1"
ROOM"IO_SLOT"
CDS_LIB"mstr_discrete"
CDS_LOCATION"R1C11"
PACK_TYPE"0402"
MATERIAL"EMPTY"
PART_NUMBER"G21497-005"
TOLERANCE"5%"
VALUE"0.0"
WATTAGE"1/16W"
LOCATION"R1C11";
"B"
$PN"2"75;
"A"
$PN"1"80;
END.
